(kicad_pcb
	(version 20260206)
	(generator "pcbnew")
	(generator_version "10.0")
	(general
		(thickness 1.6)
		(legacy_teardrops no)
	)
	(paper "A4")
	(title_block
		(title "01162023_DA0F0TEBIF0_F0T_Expander_BD_F_brd_V02_OCP.brd")
		(comment 1 "Grand Teton / footprints 8057-8062 of 9728")
	)
	(layers
		(0 "F.Cu" signal "TOP")
		(4 "In1.Cu" signal "GND")
		(6 "In2.Cu" signal "VCC")
		(8 "In3.Cu" signal "VCC1")
		(10 "In4.Cu" signal "GND1")
		(12 "In5.Cu" signal "IN1")
		(14 "In6.Cu" signal "GND2")
		(16 "In7.Cu" signal "IN2")
		(18 "In8.Cu" signal "GND3")
		(20 "In9.Cu" signal "IN3")
		(22 "In10.Cu" signal "GND4")
		(24 "In11.Cu" signal "IN4")
		(26 "In12.Cu" signal "GND5")
		(28 "In13.Cu" signal "IN5")
		(30 "In14.Cu" signal "GND6")
		(32 "In15.Cu" signal "IN6")
		(34 "In16.Cu" signal "GND7")
		(2 "B.Cu" signal "BOTTOM")
		(9 "F.Adhes" user "F.Adhesive")
		(11 "B.Adhes" user "B.Adhesive")
		(13 "F.Paste" user "Package Geometry/Pastemask Top")
		(15 "B.Paste" user "Package Geometry/Pastemask Bottom")
		(5 "F.SilkS" user "Ref Des/Silkscreen Top")
		(7 "B.SilkS" user "Ref Des/Silkscreen Bottom")
		(1 "F.Mask" user "Board Geometry/Soldermask Top")
		(3 "B.Mask" user "Board Geometry/Soldermask Bottom")
		(17 "Dwgs.User" user "User.Drawings")
		(19 "Cmts.User" user "User.Comments")
		(21 "Eco1.User" user "User.Eco1")
		(23 "Eco2.User" user "User.Eco2")
		(25 "Edge.Cuts" user "Board Geometry/Outline")
		(27 "Margin" user)
		(31 "F.CrtYd" user "Package Geometry/Place Bound Top")
		(29 "B.CrtYd" user "Package Geometry/Place Bound Bottom")
		(35 "F.Fab" user "Ref Des/Assembly Top")
		(33 "B.Fab" user "Ref Des/Assembly Bottom")
	)
	(footprint ""
		(layer "B.Cu")
		(at 106.314494 -331.550518)
		(property "Reference" "U118"
			(at 8.03529 -1.243584 0)
			(unlocked yes)
			(layer "B.SilkS")
			(effects
				(font
					(size 0.7874 0.5842)
					(thickness 0.1524)
				)
				(justify mirror)
			)
		)
		(property "Value" ""
			(at 0 0 0)
			(layer "B.Fab")
			(effects
				(font
					(size 1.27 1.27)
				)
				(justify mirror)
			)
		)
		(duplicate_pad_numbers_are_jumpers no)
		(fp_line
			(start -2.500122 -2.500122)
			(end -2.01676 -2.500122)
			(stroke
				(width 0.1524)
				(type default)
			)
			(layer "B.SilkS")
		)
		(fp_line
			(start -2.500122 -2.01676)
			(end -2.500122 -2.500122)
			(stroke
				(width 0.1524)
				(type default)
			)
			(layer "B.SilkS")
		)
		(fp_line
			(start -2.500122 2.500122)
			(end -2.500122 2.01676)
			(stroke
				(width 0.1524)
				(type default)
			)
			(layer "B.SilkS")
		)
		(fp_line
			(start -2.01676 2.500122)
			(end -2.500122 2.500122)
			(stroke
				(width 0.1524)
				(type default)
			)
			(layer "B.SilkS")
		)
		(fp_line
			(start 2.01676 -2.500122)
			(end 2.500122 -2.500122)
			(stroke
				(width 0.1524)
				(type default)
			)
			(layer "B.SilkS")
		)
		(fp_line
			(start 2.500122 -2.500122)
			(end 2.500122 -2.01676)
			(stroke
				(width 0.1524)
				(type default)
			)
			(layer "B.SilkS")
		)
		(fp_line
			(start 2.500122 2.01676)
			(end 2.500122 2.500122)
			(stroke
				(width 0.1524)
				(type default)
			)
			(layer "B.SilkS")
		)
		(fp_line
			(start 2.500122 2.500122)
			(end 2.01676 2.500122)
			(stroke
				(width 0.1524)
				(type default)
			)
			(layer "B.SilkS")
		)
		(fp_poly
			(pts
				(xy 2.54508 -2.02819) (xy 3.812794 -2.450846) (xy 2.967736 -3.295904)
			)
			(stroke
				(width 0)
				(type default)
			)
			(fill yes)
			(layer "B.SilkS")
		)
		(fp_line
			(start -2.500122 -2.500122)
			(end 2.500122 -2.500122)
			(stroke
				(width 0.1)
				(type default)
			)
			(layer "B.Fab")
		)
		(fp_line
			(start -2.500122 2.500122)
			(end -2.500122 -2.500122)
			(stroke
				(width 0.1)
				(type default)
			)
			(layer "B.Fab")
		)
		(fp_line
			(start 2.500122 -2.500122)
			(end 2.500122 2.500122)
			(stroke
				(width 0.1)
				(type default)
			)
			(layer "B.Fab")
		)
		(fp_line
			(start 2.500122 2.500122)
			(end -2.500122 2.500122)
			(stroke
				(width 0.1)
				(type default)
			)
			(layer "B.Fab")
		)
		(fp_poly
			(pts
				(xy 3.044698 -1.75006) (xy 4.240022 -1.152398) (xy 4.240022 -2.347722)
			)
			(stroke
				(width 0)
				(type default)
			)
			(fill yes)
			(layer "B.Fab")
		)
		(pad "1" smd rect
			(at 2.3749 -1.75006 270)
			(size 0.254 0.5588)
			(layers "B.Cu" "B.Mask" "B.Paste")
			(net "FM_CLK_EN_R")
		)
		(pad "2" smd rect
			(at 2.3749 -1.249934 270)
			(size 0.254 0.5588)
			(layers "B.Cu" "B.Mask" "B.Paste")
			(net "P3V3_CLK_BUFFER_9ZXL0451E_VZX3P3A")
		)
		(pad "3" smd rect
			(at 2.3749 -0.750062 270)
			(size 0.254 0.5588)
			(layers "B.Cu" "B.Mask" "B.Paste")
			(net "CLK_100M_MB_0_R_DP")
		)
		(pad "4" smd rect
			(at 2.3749 -0.249936 270)
			(size 0.254 0.5588)
			(layers "B.Cu" "B.Mask" "B.Paste")
			(net "CLK_100M_MB_0_R_DN")
		)
		(pad "5" smd rect
			(at 2.3749 0.249936 270)
			(size 0.254 0.5588)
			(layers "B.Cu" "B.Mask" "B.Paste")
			(net "SMB_9ZXL0451E_ADDR0")
		)
		(pad "6" smd rect
			(at 2.3749 0.750062 270)
			(size 0.254 0.5588)
			(layers "B.Cu" "B.Mask" "B.Paste")
			(net "SMB_BMC_9FGL0451E_SDA")
		)
		(pad "7" smd rect
			(at 2.3749 1.249934 270)
			(size 0.254 0.5588)
			(layers "B.Cu" "B.Mask" "B.Paste")
			(net "SMB_BMC_9FGL0451E_SCL")
		)
		(pad "8" smd rect
			(at 2.3749 1.75006 270)
			(size 0.254 0.5588)
			(layers "B.Cu" "B.Mask" "B.Paste")
			(net "Net_4354")
		)
		(pad "9" smd rect
			(at 1.75006 2.3749 180)
			(size 0.254 0.5588)
			(layers "B.Cu" "B.Mask" "B.Paste")
			(net "Net_4353")
		)
		(pad "10" smd rect
			(at 1.249934 2.3749 180)
			(size 0.254 0.5588)
			(layers "B.Cu" "B.Mask" "B.Paste")
			(net "Net_4355")
		)
		(pad "11" smd rect
			(at 0.750062 2.3749 180)
			(size 0.254 0.5588)
			(layers "B.Cu" "B.Mask" "B.Paste")
			(net "Net_4356")
		)
		(pad "12" smd rect
			(at 0.249936 2.3749 180)
			(size 0.254 0.5588)
			(layers "B.Cu" "B.Mask" "B.Paste")
			(net "P3V3_CLK_BUFFER_9ZXL0451E_VZX3P3")
		)
		(pad "13" smd rect
			(at -0.249936 2.3749 180)
			(size 0.254 0.5588)
			(layers "B.Cu" "B.Mask" "B.Paste")
			(net "CLK_100M_DB800ZL_PEX0_S0_DP")
		)
		(pad "14" smd rect
			(at -0.750062 2.3749 180)
			(size 0.254 0.5588)
			(layers "B.Cu" "B.Mask" "B.Paste")
			(net "CLK_100M_DB800ZL_PEX0_S0_DN")
		)
		(pad "15" smd rect
			(at -1.249934 2.3749 180)
			(size 0.254 0.5588)
			(layers "B.Cu" "B.Mask" "B.Paste")
			(net "PEX_REF_CLK_BUFFER_EN_N")
		)
		(pad "16" smd rect
			(at -1.75006 2.3749 180)
			(size 0.254 0.5588)
			(layers "B.Cu" "B.Mask" "B.Paste")
			(net "P3V3_CLK_BUFFER_9ZXL0451E_VZX3P3")
		)
		(pad "17" smd rect
			(at -2.3749 1.75006 90)
			(size 0.254 0.5588)
			(layers "B.Cu" "B.Mask" "B.Paste")
			(net "Net_4357")
		)
		(pad "18" smd rect
			(at -2.3749 1.249934 90)
			(size 0.254 0.5588)
			(layers "B.Cu" "B.Mask" "B.Paste")
			(net "PEX_REF_CLK_BUFFER_EN_N")
		)
		(pad "19" smd rect
			(at -2.3749 0.750062 90)
			(size 0.254 0.5588)
			(layers "B.Cu" "B.Mask" "B.Paste")
			(net "CLK_100M_DB800ZL_PEX1_S0_DP")
		)
		(pad "20" smd rect
			(at -2.3749 0.249936 90)
			(size 0.254 0.5588)
			(layers "B.Cu" "B.Mask" "B.Paste")
			(net "CLK_100M_DB800ZL_PEX1_S0_DN")
		)
		(pad "21" smd rect
			(at -2.3749 -0.249936 90)
			(size 0.254 0.5588)
			(layers "B.Cu" "B.Mask" "B.Paste")
			(net "P3V3_CLK_BUFFER_9ZXL0451E_VZX3P3")
		)
		(pad "22" smd rect
			(at -2.3749 -0.750062 90)
			(size 0.254 0.5588)
			(layers "B.Cu" "B.Mask" "B.Paste")
			(net "CLK_100M_DB800ZL_PEX2_S0_DP")
		)
		(pad "23" smd rect
			(at -2.3749 -1.249934 90)
			(size 0.254 0.5588)
			(layers "B.Cu" "B.Mask" "B.Paste")
			(net "CLK_100M_DB800ZL_PEX2_S0_DN")
		)
		(pad "24" smd rect
			(at -2.3749 -1.75006 90)
			(size 0.254 0.5588)
			(layers "B.Cu" "B.Mask" "B.Paste")
			(net "PEX_REF_CLK_BUFFER_EN_N")
		)
		(pad "25" smd rect
			(at -1.75006 -2.3749)
			(size 0.254 0.5588)
			(layers "B.Cu" "B.Mask" "B.Paste")
			(net "P3V3_CLK_BUFFER_9ZXL0451E_VZX3P3")
		)
		(pad "26" smd rect
			(at -1.249934 -2.3749)
			(size 0.254 0.5588)
			(layers "B.Cu" "B.Mask" "B.Paste")
			(net "PEX_REF_CLK_BUFFER_EN_N")
		)
		(pad "27" smd rect
			(at -0.750062 -2.3749)
			(size 0.254 0.5588)
			(layers "B.Cu" "B.Mask" "B.Paste")
			(net "CLK_100M_DB800ZL_PEX3_S0_DP")
		)
		(pad "28" smd rect
			(at -0.249936 -2.3749)
			(size 0.254 0.5588)
			(layers "B.Cu" "B.Mask" "B.Paste")
			(net "CLK_100M_DB800ZL_PEX3_S0_DN")
		)
		(pad "29" smd rect
			(at 0.249936 -2.3749)
			(size 0.254 0.5588)
			(layers "B.Cu" "B.Mask" "B.Paste")
			(net "P3V3_CLK_BUFFER_9ZXL0451E_VZX3P3")
		)
		(pad "30" smd rect
			(at 0.750062 -2.3749)
			(size 0.254 0.5588)
			(layers "B.Cu" "B.Mask" "B.Paste")
			(net "Net_4358")
		)
		(pad "31" smd rect
			(at 1.249934 -2.3749)
			(size 0.254 0.5588)
			(layers "B.Cu" "B.Mask" "B.Paste")
			(net "P3V3_CLK_BUFFER_9ZXL0451E_VZX3P3A")
		)
		(pad "32" smd rect
			(at 1.75006 -2.3749)
			(size 0.254 0.5588)
			(layers "B.Cu" "B.Mask" "B.Paste")
			(net "PU_9ZXL0451E_HBW")
		)
		(pad "33" smd rect
			(at 0 0 180)
			(size 3.1496 3.1496)
			(layers "B.Cu" "B.Mask" "B.Paste")
			(net "GND")
		)
		(zone
			(layer "B.Cu")
			(hatch none 0.5)
			(connect_pads
				(clearance 0)
			)
			(min_thickness 0.25)
			(keepout
				(tracks not_allowed)
				(vias allowed)
				(pads allowed)
				(copperpour not_allowed)
				(footprints allowed)
			)
			(placement
				(enabled no)
				(sheetname "")
			)
			(fill
				(thermal_gap 0.5)
				(thermal_bridge_width 0.5)
				(island_removal_mode 0)
			)
			(polygon
				(pts
					(xy 108.359194 -329.505818) (xy 108.359194 -332.775052) (xy 107.940094 -332.775052) (xy 107.940094 -329.924918)
					(xy 104.688894 -329.924918) (xy 104.688894 -333.176118) (xy 107.940094 -333.176118) (xy 107.940094 -332.800452)
					(xy 108.359194 -332.800452) (xy 108.359194 -333.595218) (xy 104.269794 -333.595218) (xy 104.269794 -329.505818)
				)
			)
		)
	)
	(footprint ""
		(layer "B.Cu")
		(at 70.099936 -289.724846 180)
		(property "Reference" "C3003"
			(at 0 0 0)
			(layer "B.SilkS")
			(hide yes)
			(effects
				(font
					(size 1.27 1.27)
				)
				(justify mirror)
			)
		)
		(property "Value" ""
			(at 0 0 0)
			(layer "B.Fab")
			(effects
				(font
					(size 1.27 1.27)
				)
				(justify mirror)
			)
		)
		(duplicate_pad_numbers_are_jumpers no)
		(fp_line
			(start 0.299974 0.150114)
			(end 0.299974 -0.150114)
			(stroke
				(width 0.1)
				(type default)
			)
			(layer "B.Fab")
		)
		(fp_line
			(start 0.299974 -0.150114)
			(end -0.299974 -0.150114)
			(stroke
				(width 0.1)
				(type default)
			)
			(layer "B.Fab")
		)
		(fp_line
			(start -0.299974 0.150114)
			(end 0.299974 0.150114)
			(stroke
				(width 0.1)
				(type default)
			)
			(layer "B.Fab")
		)
		(fp_line
			(start -0.299974 -0.150114)
			(end -0.299974 0.150114)
			(stroke
				(width 0.1)
				(type default)
			)
			(layer "B.Fab")
		)
		(pad "1" smd rect
			(at 0.2667 0)
			(size 0.3048 0.381)
			(layers "B.Cu" "B.Mask" "B.Paste")
			(net "P1V8_PEX")
		)
		(pad "2" smd rect
			(at -0.2667 0)
			(size 0.3048 0.381)
			(layers "B.Cu" "B.Mask" "B.Paste")
			(net "GND")
		)
	)
	(footprint ""
		(layer "B.Cu")
		(at 329.692 -224.4852)
		(property "Reference" "R4166"
			(at 0 0 0)
			(layer "B.SilkS")
			(hide yes)
			(effects
				(font
					(size 1.27 1.27)
				)
				(justify mirror)
			)
		)
		(property "Value" ""
			(at 0 0 0)
			(layer "B.Fab")
			(effects
				(font
					(size 1.27 1.27)
				)
				(justify mirror)
			)
		)
		(duplicate_pad_numbers_are_jumpers no)
		(fp_line
			(start -0.7874 -0.4064)
			(end -0.7874 0.4064)
			(stroke
				(width 0.1524)
				(type default)
			)
			(layer "B.SilkS")
		)
		(fp_line
			(start -0.7874 0.4064)
			(end 0.7874 0.4064)
			(stroke
				(width 0.1524)
				(type default)
			)
			(layer "B.SilkS")
		)
		(fp_line
			(start 0.7874 -0.4064)
			(end -0.7874 -0.4064)
			(stroke
				(width 0.1524)
				(type default)
			)
			(layer "B.SilkS")
		)
		(fp_line
			(start 0.7874 0.4064)
			(end 0.7874 -0.4064)
			(stroke
				(width 0.1524)
				(type default)
			)
			(layer "B.SilkS")
		)
		(fp_line
			(start -0.67945 -0.3048)
			(end -0.67945 0.3048)
			(stroke
				(width 0.1)
				(type default)
			)
			(layer "B.Fab")
		)
		(fp_line
			(start -0.67945 0.3048)
			(end -0.120396 0.3048)
			(stroke
				(width 0.1)
				(type default)
			)
			(layer "B.Fab")
		)
		(fp_line
			(start -0.12065 -0.3048)
			(end -0.67945 -0.3048)
			(stroke
				(width 0.1)
				(type default)
			)
			(layer "B.Fab")
		)
		(fp_line
			(start -0.12065 -0.2794)
			(end -0.12065 -0.3048)
			(stroke
				(width 0.1)
				(type default)
			)
			(layer "B.Fab")
		)
		(fp_line
			(start -0.120396 0.2794)
			(end 0.12065 0.2794)
			(stroke
				(width 0.1)
				(type default)
			)
			(layer "B.Fab")
		)
		(fp_line
			(start -0.120396 0.3048)
			(end -0.120396 0.2794)
			(stroke
				(width 0.1)
				(type default)
			)
			(layer "B.Fab")
		)
		(fp_line
			(start 0.12065 -0.305054)
			(end 0.12065 -0.2794)
			(stroke
				(width 0.1)
				(type default)
			)
			(layer "B.Fab")
		)
		(fp_line
			(start 0.12065 -0.2794)
			(end -0.12065 -0.2794)
			(stroke
				(width 0.1)
				(type default)
			)
			(layer "B.Fab")
		)
		(fp_line
			(start 0.12065 0.2794)
			(end 0.12065 0.3048)
			(stroke
				(width 0.1)
				(type default)
			)
			(layer "B.Fab")
		)
		(fp_line
			(start 0.12065 0.3048)
			(end 0.67945 0.3048)
			(stroke
				(width 0.1)
				(type default)
			)
			(layer "B.Fab")
		)
		(fp_line
			(start 0.67945 -0.305054)
			(end 0.12065 -0.305054)
			(stroke
				(width 0.1)
				(type default)
			)
			(layer "B.Fab")
		)
		(fp_line
			(start 0.67945 0.3048)
			(end 0.67945 -0.305054)
			(stroke
				(width 0.1)
				(type default)
			)
			(layer "B.Fab")
		)
		(pad "1" smd circle
			(at 0.40005 0 180)
			(size 0 0)
			(layers "B.Cu" "B.Mask" "B.Paste")
			(net "PWR_EN_P3V3")
		)
		(pad "2" smd circle
			(at -0.40005 0 180)
			(size 0 0)
			(layers "B.Cu" "B.Mask" "B.Paste")
			(net "PWR_EN_P3V3_R")
		)
	)
	(footprint ""
		(layer "B.Cu")
		(at 425.841922 -101.069648 180)
		(property "Reference" "R382"
			(at 0 0 0)
			(layer "B.SilkS")
			(hide yes)
			(effects
				(font
					(size 1.27 1.27)
				)
				(justify mirror)
			)
		)
		(property "Value" ""
			(at 0 0 0)
			(layer "B.Fab")
			(effects
				(font
					(size 1.27 1.27)
				)
				(justify mirror)
			)
		)
		(duplicate_pad_numbers_are_jumpers no)
		(fp_line
			(start 0.7874 0.4064)
			(end 0.7874 -0.4064)
			(stroke
				(width 0.1524)
				(type default)
			)
			(layer "B.SilkS")
		)
		(fp_line
			(start 0.7874 -0.4064)
			(end -0.7874 -0.4064)
			(stroke
				(width 0.1524)
				(type default)
			)
			(layer "B.SilkS")
		)
		(fp_line
			(start -0.7874 0.4064)
			(end 0.7874 0.4064)
			(stroke
				(width 0.1524)
				(type default)
			)
			(layer "B.SilkS")
		)
		(fp_line
			(start -0.7874 -0.4064)
			(end -0.7874 0.4064)
			(stroke
				(width 0.1524)
				(type default)
			)
			(layer "B.SilkS")
		)
		(fp_line
			(start 0.67945 0.3048)
			(end 0.67945 -0.305054)
			(stroke
				(width 0.1)
				(type default)
			)
			(layer "B.Fab")
		)
		(fp_line
			(start 0.67945 -0.305054)
			(end 0.12065 -0.305054)
			(stroke
				(width 0.1)
				(type default)
			)
			(layer "B.Fab")
		)
		(fp_line
			(start 0.12065 0.3048)
			(end 0.67945 0.3048)
			(stroke
				(width 0.1)
				(type default)
			)
			(layer "B.Fab")
		)
		(fp_line
			(start 0.12065 0.2794)
			(end 0.12065 0.3048)
			(stroke
				(width 0.1)
				(type default)
			)
			(layer "B.Fab")
		)
		(fp_line
			(start 0.12065 -0.2794)
			(end -0.12065 -0.2794)
			(stroke
				(width 0.1)
				(type default)
			)
			(layer "B.Fab")
		)
		(fp_line
			(start 0.12065 -0.305054)
			(end 0.12065 -0.2794)
			(stroke
				(width 0.1)
				(type default)
			)
			(layer "B.Fab")
		)
		(fp_line
			(start -0.120396 0.3048)
			(end -0.120396 0.2794)
			(stroke
				(width 0.1)
				(type default)
			)
			(layer "B.Fab")
		)
		(fp_line
			(start -0.120396 0.2794)
			(end 0.12065 0.2794)
			(stroke
				(width 0.1)
				(type default)
			)
			(layer "B.Fab")
		)
		(fp_line
			(start -0.12065 -0.2794)
			(end -0.12065 -0.3048)
			(stroke
				(width 0.1)
				(type default)
			)
			(layer "B.Fab")
		)
		(fp_line
			(start -0.12065 -0.3048)
			(end -0.67945 -0.3048)
			(stroke
				(width 0.1)
				(type default)
			)
			(layer "B.Fab")
		)
		(fp_line
			(start -0.67945 0.3048)
			(end -0.120396 0.3048)
			(stroke
				(width 0.1)
				(type default)
			)
			(layer "B.Fab")
		)
		(fp_line
			(start -0.67945 -0.3048)
			(end -0.67945 0.3048)
			(stroke
				(width 0.1)
				(type default)
			)
			(layer "B.Fab")
		)
		(pad "1" smd circle
			(at 0.40005 0)
			(size 0 0)
			(layers "B.Cu" "B.Mask" "B.Paste")
			(net "NIC7_SLOT_ID0")
		)
		(pad "2" smd circle
			(at -0.40005 0)
			(size 0 0)
			(layers "B.Cu" "B.Mask" "B.Paste")
			(net "P3V3_NIC7")
		)
	)
	(footprint ""
		(layer "B.Cu")
		(at 54.899814 -303.499774 -90)
		(property "Reference" "C2912"
			(at 0 0 90)
			(layer "B.SilkS")
			(hide yes)
			(effects
				(font
					(size 1.27 1.27)
				)
				(justify mirror)
			)
		)
		(property "Value" ""
			(at 0 0 90)
			(layer "B.Fab")
			(effects
				(font
					(size 1.27 1.27)
				)
				(justify mirror)
			)
		)
		(duplicate_pad_numbers_are_jumpers no)
		(fp_line
			(start -0.299974 0.150114)
			(end 0.299974 0.150114)
			(stroke
				(width 0.1)
				(type default)
			)
			(layer "B.Fab")
		)
		(fp_line
			(start 0.299974 0.150114)
			(end 0.299974 -0.150114)
			(stroke
				(width 0.1)
				(type default)
			)
			(layer "B.Fab")
		)
		(fp_line
			(start -0.299974 -0.150114)
			(end -0.299974 0.150114)
			(stroke
				(width 0.1)
				(type default)
			)
			(layer "B.Fab")
		)
		(fp_line
			(start 0.299974 -0.150114)
			(end -0.299974 -0.150114)
			(stroke
				(width 0.1)
				(type default)
			)
			(layer "B.Fab")
		)
		(pad "1" smd rect
			(at 0.2667 0 90)
			(size 0.3048 0.381)
			(layers "B.Cu" "B.Mask" "B.Paste")
			(net "P1V25_PEX0")
		)
		(pad "2" smd rect
			(at -0.2667 0 90)
			(size 0.3048 0.381)
			(layers "B.Cu" "B.Mask" "B.Paste")
			(net "GND")
		)
	)
	(footprint ""
		(layer "B.Cu")
		(at 296.599864 -303.499774 -90)
		(property "Reference" "C3267"
			(at 0 0 90)
			(layer "B.SilkS")
			(hide yes)
			(effects
				(font
					(size 1.27 1.27)
				)
				(justify mirror)
			)
		)
		(property "Value" ""
			(at 0 0 90)
			(layer "B.Fab")
			(effects
				(font
					(size 1.27 1.27)
				)
				(justify mirror)
			)
		)
		(duplicate_pad_numbers_are_jumpers no)
		(fp_line
			(start -0.299974 0.150114)
			(end 0.299974 0.150114)
			(stroke
				(width 0.1)
				(type default)
			)
			(layer "B.Fab")
		)
		(fp_line
			(start 0.299974 0.150114)
			(end 0.299974 -0.150114)
			(stroke
				(width 0.1)
				(type default)
			)
			(layer "B.Fab")
		)
		(fp_line
			(start -0.299974 -0.150114)
			(end -0.299974 0.150114)
			(stroke
				(width 0.1)
				(type default)
			)
			(layer "B.Fab")
		)
		(fp_line
			(start 0.299974 -0.150114)
			(end -0.299974 -0.150114)
			(stroke
				(width 0.1)
				(type default)
			)
			(layer "B.Fab")
		)
		(pad "1" smd rect
			(at 0.2667 0 90)
			(size 0.3048 0.381)
			(layers "B.Cu" "B.Mask" "B.Paste")
			(net "P1V25_PEX2")
		)
		(pad "2" smd rect
			(at -0.2667 0 90)
			(size 0.3048 0.381)
			(layers "B.Cu" "B.Mask" "B.Paste")
			(net "GND")
		)
	)
)
